(kicad_pcb
	(version 20260206)
	(generator "pcbnew")
	(generator_version "10.0")
	(general
		(thickness 1.6)
		(legacy_teardrops no)
	)
	(paper "A4")
	(title_block
		(title "Wiwynn_Tioga_Pass_MB.brd")
		(comment 1 "Tioga Pass / footprint 2717 of 4770 (J9L1), pads 244-291 of 291")
	)
	(layers
		(0 "F.Cu" signal "TOP")
		(4 "In1.Cu" signal "L2GND")
		(6 "In2.Cu" signal "L3")
		(8 "In3.Cu" signal "L4GND")
		(10 "In4.Cu" signal "L5")
		(12 "In5.Cu" signal "L6GND")
		(14 "In6.Cu" signal "L7VCC")
		(16 "In7.Cu" signal "L8VCC")
		(18 "In8.Cu" signal "L9GND")
		(20 "In9.Cu" signal "L10")
		(22 "In10.Cu" signal "L11GND")
		(24 "In11.Cu" signal "L12")
		(26 "In12.Cu" signal "L13GND")
		(2 "B.Cu" signal "BOTTOM")
		(9 "F.Adhes" user "F.Adhesive")
		(11 "B.Adhes" user "B.Adhesive")
		(13 "F.Paste" user "Package Geometry/Pastemask Top")
		(15 "B.Paste" user "Package Geometry/Pastemask Bottom")
		(5 "F.SilkS" user "Ref Des/Silkscreen Top")
		(7 "B.SilkS" user "Ref Des/Silkscreen Bottom")
		(1 "F.Mask" user "Board Geometry/Soldermask Top")
		(3 "B.Mask" user "Board Geometry/Soldermask Bottom")
		(17 "Dwgs.User" user "User.Drawings")
		(19 "Cmts.User" user "User.Comments")
		(21 "Eco1.User" user "User.Eco1")
		(23 "Eco2.User" user "User.Eco2")
		(25 "Edge.Cuts" user "Board Geometry/Outline")
		(27 "Margin" user)
		(31 "F.CrtYd" user "Package Geometry/Place Bound Top")
		(29 "B.CrtYd" user "Package Geometry/Place Bound Bottom")
		(35 "F.Fab" user "Ref Des/Assembly Top")
		(33 "B.Fab" user "Ref Des/Assembly Bottom")
	)
	(footprint ""
		(layer "B.Cu")
		(at 29.699458 -152.078436 90)
		(property "Reference" "J9L1"
			(at 2.200148 37.737542 0)
			(unlocked yes)
			(layer "B.SilkS")
			(effects
				(font
					(size 0.7874 0.5842)
					(thickness 0.1524)
				)
				(justify left mirror)
			)
		)
		(property "Value" ""
			(at 0 0 90)
			(layer "B.Fab")
			(effects
				(font
					(size 1.27 1.27)
				)
				(justify mirror)
			)
		)
		(duplicate_pad_numbers_are_jumpers no)
		(pad "241" smd rect
			(at -4.59994 86.700106 270)
			(size 1.8034 0.508)
			(layers "B.Cu" "B.Mask" "B.Paste")
			(net "GND")
		)
		(pad "242" smd rect
			(at -4.59994 87.54999 270)
			(size 1.8034 0.508)
			(layers "B.Cu" "B.Mask" "B.Paste")
			(net "M_M_DQ<33>")
		)
		(pad "243" smd rect
			(at -4.59994 88.399874 270)
			(size 1.8034 0.508)
			(layers "B.Cu" "B.Mask" "B.Paste")
			(net "GND")
		)
		(pad "244" smd rect
			(at -4.59994 89.250012 270)
			(size 1.8034 0.508)
			(layers "B.Cu" "B.Mask" "B.Paste")
			(net "M_M_DQS_DN<4>")
		)
		(pad "245" smd rect
			(at -4.59994 90.099896 270)
			(size 1.8034 0.508)
			(layers "B.Cu" "B.Mask" "B.Paste")
			(net "M_M_DQS_DP<4>")
		)
		(pad "246" smd rect
			(at -4.59994 90.950034 270)
			(size 1.8034 0.508)
			(layers "B.Cu" "B.Mask" "B.Paste")
			(net "GND")
		)
		(pad "247" smd rect
			(at -4.59994 91.799918 270)
			(size 1.8034 0.508)
			(layers "B.Cu" "B.Mask" "B.Paste")
			(net "M_M_DQ<39>")
		)
		(pad "248" smd rect
			(at -4.59994 92.650056 270)
			(size 1.8034 0.508)
			(layers "B.Cu" "B.Mask" "B.Paste")
			(net "GND")
		)
		(pad "249" smd rect
			(at -4.59994 93.49994 270)
			(size 1.8034 0.508)
			(layers "B.Cu" "B.Mask" "B.Paste")
			(net "M_M_DQ<35>")
		)
		(pad "250" smd rect
			(at -4.59994 94.350078 270)
			(size 1.8034 0.508)
			(layers "B.Cu" "B.Mask" "B.Paste")
			(net "GND")
		)
		(pad "251" smd rect
			(at -4.59994 95.199962 270)
			(size 1.8034 0.508)
			(layers "B.Cu" "B.Mask" "B.Paste")
			(net "M_M_DQ<45>")
		)
		(pad "252" smd rect
			(at -4.59994 96.0501 270)
			(size 1.8034 0.508)
			(layers "B.Cu" "B.Mask" "B.Paste")
			(net "GND")
		)
		(pad "253" smd rect
			(at -4.59994 96.899984 270)
			(size 1.8034 0.508)
			(layers "B.Cu" "B.Mask" "B.Paste")
			(net "M_M_DQ<41>")
		)
		(pad "254" smd rect
			(at -4.59994 97.750122 270)
			(size 1.8034 0.508)
			(layers "B.Cu" "B.Mask" "B.Paste")
			(net "GND")
		)
		(pad "255" smd rect
			(at -4.59994 98.600006 270)
			(size 1.8034 0.508)
			(layers "B.Cu" "B.Mask" "B.Paste")
			(net "M_M_DQS_DN<5>")
		)
		(pad "256" smd rect
			(at -4.59994 99.44989 270)
			(size 1.8034 0.508)
			(layers "B.Cu" "B.Mask" "B.Paste")
			(net "M_M_DQS_DP<5>")
		)
		(pad "257" smd rect
			(at -4.59994 100.300028 270)
			(size 1.8034 0.508)
			(layers "B.Cu" "B.Mask" "B.Paste")
			(net "GND")
		)
		(pad "258" smd rect
			(at -4.59994 101.149912 270)
			(size 1.8034 0.508)
			(layers "B.Cu" "B.Mask" "B.Paste")
			(net "M_M_DQ<47>")
		)
		(pad "259" smd rect
			(at -4.59994 102.00005 270)
			(size 1.8034 0.508)
			(layers "B.Cu" "B.Mask" "B.Paste")
			(net "GND")
		)
		(pad "260" smd rect
			(at -4.59994 102.849934 270)
			(size 1.8034 0.508)
			(layers "B.Cu" "B.Mask" "B.Paste")
			(net "M_M_DQ<43>")
		)
		(pad "261" smd rect
			(at -4.59994 103.700072 270)
			(size 1.8034 0.508)
			(layers "B.Cu" "B.Mask" "B.Paste")
			(net "GND")
		)
		(pad "262" smd rect
			(at -4.59994 104.549956 270)
			(size 1.8034 0.508)
			(layers "B.Cu" "B.Mask" "B.Paste")
			(net "M_M_DQ<53>")
		)
		(pad "263" smd rect
			(at -4.59994 105.400094 270)
			(size 1.8034 0.508)
			(layers "B.Cu" "B.Mask" "B.Paste")
			(net "GND")
		)
		(pad "264" smd rect
			(at -4.59994 106.249978 270)
			(size 1.8034 0.508)
			(layers "B.Cu" "B.Mask" "B.Paste")
			(net "M_M_DQ<49>")
		)
		(pad "265" smd rect
			(at -4.59994 107.100116 270)
			(size 1.8034 0.508)
			(layers "B.Cu" "B.Mask" "B.Paste")
			(net "GND")
		)
		(pad "266" smd rect
			(at -4.59994 107.95 270)
			(size 1.8034 0.508)
			(layers "B.Cu" "B.Mask" "B.Paste")
			(net "M_M_DQS_DN<6>")
		)
		(pad "267" smd rect
			(at -4.59994 108.799884 270)
			(size 1.8034 0.508)
			(layers "B.Cu" "B.Mask" "B.Paste")
			(net "M_M_DQS_DP<6>")
		)
		(pad "268" smd rect
			(at -4.59994 109.650022 270)
			(size 1.8034 0.508)
			(layers "B.Cu" "B.Mask" "B.Paste")
			(net "GND")
		)
		(pad "269" smd rect
			(at -4.59994 110.499906 270)
			(size 1.8034 0.508)
			(layers "B.Cu" "B.Mask" "B.Paste")
			(net "M_M_DQ<55>")
		)
		(pad "270" smd rect
			(at -4.59994 111.350044 270)
			(size 1.8034 0.508)
			(layers "B.Cu" "B.Mask" "B.Paste")
			(net "GND")
		)
		(pad "271" smd rect
			(at -4.59994 112.199928 270)
			(size 1.8034 0.508)
			(layers "B.Cu" "B.Mask" "B.Paste")
			(net "M_M_DQ<51>")
		)
		(pad "272" smd rect
			(at -4.59994 113.050066 270)
			(size 1.8034 0.508)
			(layers "B.Cu" "B.Mask" "B.Paste")
			(net "GND")
		)
		(pad "273" smd rect
			(at -4.59994 113.89995 270)
			(size 1.8034 0.508)
			(layers "B.Cu" "B.Mask" "B.Paste")
			(net "M_M_DQ<61>")
		)
		(pad "274" smd rect
			(at -4.59994 114.750088 270)
			(size 1.8034 0.508)
			(layers "B.Cu" "B.Mask" "B.Paste")
			(net "GND")
		)
		(pad "275" smd rect
			(at -4.59994 115.599972 270)
			(size 1.8034 0.508)
			(layers "B.Cu" "B.Mask" "B.Paste")
			(net "M_M_DQ<57>")
		)
		(pad "276" smd rect
			(at -4.59994 116.45011 270)
			(size 1.8034 0.508)
			(layers "B.Cu" "B.Mask" "B.Paste")
			(net "GND")
		)
		(pad "277" smd rect
			(at -4.59994 117.299994 270)
			(size 1.8034 0.508)
			(layers "B.Cu" "B.Mask" "B.Paste")
			(net "M_M_DQS_DN<7>")
		)
		(pad "278" smd rect
			(at -4.59994 118.149878 270)
			(size 1.8034 0.508)
			(layers "B.Cu" "B.Mask" "B.Paste")
			(net "M_M_DQS_DP<7>")
		)
		(pad "279" smd rect
			(at -4.59994 119.000016 270)
			(size 1.8034 0.508)
			(layers "B.Cu" "B.Mask" "B.Paste")
			(net "GND")
		)
		(pad "280" smd rect
			(at -4.59994 119.8499 270)
			(size 1.8034 0.508)
			(layers "B.Cu" "B.Mask" "B.Paste")
			(net "M_M_DQ<63>")
		)
		(pad "281" smd rect
			(at -4.59994 120.700038 270)
			(size 1.8034 0.508)
			(layers "B.Cu" "B.Mask" "B.Paste")
			(net "GND")
		)
		(pad "282" smd rect
			(at -4.59994 121.549922 270)
			(size 1.8034 0.508)
			(layers "B.Cu" "B.Mask" "B.Paste")
			(net "M_M_DQ<59>")
		)
		(pad "283" smd rect
			(at -4.59994 122.40006 270)
			(size 1.8034 0.508)
			(layers "B.Cu" "B.Mask" "B.Paste")
			(net "GND")
		)
		(pad "284" smd rect
			(at -4.59994 123.249944 270)
			(size 1.8034 0.508)
			(layers "B.Cu" "B.Mask" "B.Paste")
			(net "PVPP_KLM")
		)
		(pad "285" smd rect
			(at -4.59994 124.100082 270)
			(size 1.8034 0.508)
			(layers "B.Cu" "B.Mask" "B.Paste")
			(net "SMB_DDR_KLM_VPP_SDA")
		)
		(pad "286" smd rect
			(at -4.59994 124.949966 270)
			(size 1.8034 0.508)
			(layers "B.Cu" "B.Mask" "B.Paste")
			(net "PVPP_KLM")
		)
		(pad "287" smd rect
			(at -4.59994 125.800104 270)
			(size 1.8034 0.508)
			(layers "B.Cu" "B.Mask" "B.Paste")
			(net "PVPP_KLM")
		)
		(pad "288" smd rect
			(at -4.59994 126.649988 270)
			(size 1.8034 0.508)
			(layers "B.Cu" "B.Mask" "B.Paste")
			(net "PVPP_KLM")
		)
	)
)
